# SCM (Grand Teton) — schematic netlist excerpt (pin names and nets, part order shuffled) for the footprints in the layout excerpt that follows; sources: Cadence DE-HDL packaged netlist, KiCad conversion of 12092022_DA0F0TMDCD0_F0T_Management_Board_D_brd_V3_OCP.brd

R146  Q_RES  33.2 1% CHIP  pkg 0402LF  page 12 : A = SMB_BMC_MM8_R_SCL ; B = SMB_BMC_MM8_SCL
R735  Q_RES  1K 1% CHIP  pkg 0402LF  page 28 : A = P3V3_AUX ; B = FM_UART_SWITCH_N

(kicad_pcb
	(version 20260206)
	(generator "pcbnew")
	(generator_version "10.0")
	(general
		(thickness 1.6)
		(legacy_teardrops no)
	)
	(paper "A4")
	(title_block
		(title "12092022_DA0F0TMDCD0_F0T_Management_Board_D_brd_V3_OCP.brd")
		(comment 1 "Grand Teton / footprints 994-995 of 1440")
	)
	(layers
		(0 "F.Cu" signal "TOP")
		(4 "In1.Cu" signal "GND")
		(6 "In2.Cu" signal "IN1")
		(8 "In3.Cu" signal "GND1")
		(10 "In4.Cu" signal "IN2")
		(12 "In5.Cu" signal "VCC")
		(14 "In6.Cu" signal "VCC1")
		(16 "In7.Cu" signal "IN3")
		(18 "In8.Cu" signal "GND2")
		(20 "In9.Cu" signal "IN4")
		(22 "In10.Cu" signal "GND3")
		(2 "B.Cu" signal "BOTTOM")
		(9 "F.Adhes" user "F.Adhesive")
		(11 "B.Adhes" user "B.Adhesive")
		(13 "F.Paste" user "Package Geometry/Pastemask Top")
		(15 "B.Paste" user "Package Geometry/Pastemask Bottom")
		(5 "F.SilkS" user "Ref Des/Silkscreen Top")
		(7 "B.SilkS" user "Ref Des/Silkscreen Bottom")
		(1 "F.Mask" user "Board Geometry/Soldermask Top")
		(3 "B.Mask" user "Board Geometry/Soldermask Bottom")
		(17 "Dwgs.User" user "User.Drawings")
		(19 "Cmts.User" user "User.Comments")
		(21 "Eco1.User" user "User.Eco1")
		(23 "Eco2.User" user "User.Eco2")
		(25 "Edge.Cuts" user "Board Geometry/Outline")
		(27 "Margin" user)
		(31 "F.CrtYd" user "Package Geometry/Place Bound Top")
		(29 "B.CrtYd" user "Package Geometry/Place Bound Bottom")
		(35 "F.Fab" user "Ref Des/Assembly Top")
		(33 "B.Fab" user "Ref Des/Assembly Bottom")
	)
	(footprint ""
		(layer "B.Cu")
		(at 56.515 -34.671 90)
		(property "Reference" "R146"
			(at 0 0 90)
			(layer "B.SilkS")
			(hide yes)
			(effects
				(font
					(size 1.27 1.27)
				)
				(justify mirror)
			)
		)
		(property "Value" ""
			(at 0 0 90)
			(layer "B.Fab")
			(effects
				(font
					(size 1.27 1.27)
				)
				(justify mirror)
			)
		)
		(duplicate_pad_numbers_are_jumpers no)
		(fp_line
			(start 0.7874 -0.4064)
			(end -0.7874 -0.4064)
			(stroke
				(width 0.1524)
				(type default)
			)
			(layer "B.SilkS")
		)
		(fp_line
			(start -0.7874 -0.4064)
			(end -0.7874 0.4064)
			(stroke
				(width 0.1524)
				(type default)
			)
			(layer "B.SilkS")
		)
		(fp_line
			(start 0.7874 0.4064)
			(end 0.7874 -0.4064)
			(stroke
				(width 0.1524)
				(type default)
			)
			(layer "B.SilkS")
		)
		(fp_line
			(start -0.7874 0.4064)
			(end 0.7874 0.4064)
			(stroke
				(width 0.1524)
				(type default)
			)
			(layer "B.SilkS")
		)
		(fp_line
			(start 0.67945 -0.305054)
			(end 0.12065 -0.305054)
			(stroke
				(width 0.1)
				(type default)
			)
			(layer "B.Fab")
		)
		(fp_line
			(start 0.12065 -0.305054)
			(end 0.12065 -0.2794)
			(stroke
				(width 0.1)
				(type default)
			)
			(layer "B.Fab")
		)
		(fp_line
			(start -0.12065 -0.3048)
			(end -0.67945 -0.3048)
			(stroke
				(width 0.1)
				(type default)
			)
			(layer "B.Fab")
		)
		(fp_line
			(start -0.67945 -0.3048)
			(end -0.67945 0.3048)
			(stroke
				(width 0.1)
				(type default)
			)
			(layer "B.Fab")
		)
		(fp_line
			(start 0.12065 -0.2794)
			(end -0.12065 -0.2794)
			(stroke
				(width 0.1)
				(type default)
			)
			(layer "B.Fab")
		)
		(fp_line
			(start -0.12065 -0.2794)
			(end -0.12065 -0.3048)
			(stroke
				(width 0.1)
				(type default)
			)
			(layer "B.Fab")
		)
		(fp_line
			(start 0.12065 0.2794)
			(end 0.12065 0.3048)
			(stroke
				(width 0.1)
				(type default)
			)
			(layer "B.Fab")
		)
		(fp_line
			(start -0.120396 0.2794)
			(end 0.12065 0.2794)
			(stroke
				(width 0.1)
				(type default)
			)
			(layer "B.Fab")
		)
		(fp_line
			(start 0.67945 0.3048)
			(end 0.67945 -0.305054)
			(stroke
				(width 0.1)
				(type default)
			)
			(layer "B.Fab")
		)
		(fp_line
			(start 0.12065 0.3048)
			(end 0.67945 0.3048)
			(stroke
				(width 0.1)
				(type default)
			)
			(layer "B.Fab")
		)
		(fp_line
			(start -0.120396 0.3048)
			(end -0.120396 0.2794)
			(stroke
				(width 0.1)
				(type default)
			)
			(layer "B.Fab")
		)
		(fp_line
			(start -0.67945 0.3048)
			(end -0.120396 0.3048)
			(stroke
				(width 0.1)
				(type default)
			)
			(layer "B.Fab")
		)
		(pad "1" smd circle
			(at 0.40005 0 270)
			(size 0 0)
			(layers "B.Cu" "B.Mask" "B.Paste")
			(net "SMB_BMC_MM8_R_SCL")
		)
		(pad "2" smd circle
			(at -0.40005 0 270)
			(size 0 0)
			(layers "B.Cu" "B.Mask" "B.Paste")
			(net "SMB_BMC_MM8_SCL")
		)
	)
	(footprint ""
		(layer "B.Cu")
		(at 51.2445 -91.3765 180)
		(property "Reference" "R735"
			(at 0 0 0)
			(layer "B.SilkS")
			(hide yes)
			(effects
				(font
					(size 1.27 1.27)
				)
				(justify mirror)
			)
		)
		(property "Value" ""
			(at 0 0 0)
			(layer "B.Fab")
			(effects
				(font
					(size 1.27 1.27)
				)
				(justify mirror)
			)
		)
		(duplicate_pad_numbers_are_jumpers no)
		(fp_line
			(start 0.7874 0.4064)
			(end 0.7874 -0.4064)
			(stroke
				(width 0.1524)
				(type default)
			)
			(layer "B.SilkS")
		)
		(fp_line
			(start 0.7874 -0.4064)
			(end -0.7874 -0.4064)
			(stroke
				(width 0.1524)
				(type default)
			)
			(layer "B.SilkS")
		)
		(fp_line
			(start -0.7874 0.4064)
			(end 0.7874 0.4064)
			(stroke
				(width 0.1524)
				(type default)
			)
			(layer "B.SilkS")
		)
		(fp_line
			(start -0.7874 -0.4064)
			(end -0.7874 0.4064)
			(stroke
				(width 0.1524)
				(type default)
			)
			(layer "B.SilkS")
		)
		(fp_line
			(start 0.67945 0.3048)
			(end 0.67945 -0.305054)
			(stroke
				(width 0.1)
				(type default)
			)
			(layer "B.Fab")
		)
		(fp_line
			(start 0.67945 -0.305054)
			(end 0.12065 -0.305054)
			(stroke
				(width 0.1)
				(type default)
			)
			(layer "B.Fab")
		)
		(fp_line
			(start 0.12065 0.3048)
			(end 0.67945 0.3048)
			(stroke
				(width 0.1)
				(type default)
			)
			(layer "B.Fab")
		)
		(fp_line
			(start 0.12065 0.2794)
			(end 0.12065 0.3048)
			(stroke
				(width 0.1)
				(type default)
			)
			(layer "B.Fab")
		)
		(fp_line
			(start 0.12065 -0.2794)
			(end -0.12065 -0.2794)
			(stroke
				(width 0.1)
				(type default)
			)
			(layer "B.Fab")
		)
		(fp_line
			(start 0.12065 -0.305054)
			(end 0.12065 -0.2794)
			(stroke
				(width 0.1)
				(type default)
			)
			(layer "B.Fab")
		)
		(fp_line
			(start -0.120396 0.3048)
			(end -0.120396 0.2794)
			(stroke
				(width 0.1)
				(type default)
			)
			(layer "B.Fab")
		)
		(fp_line
			(start -0.120396 0.2794)
			(end 0.12065 0.2794)
			(stroke
				(width 0.1)
				(type default)
			)
			(layer "B.Fab")
		)
		(fp_line
			(start -0.12065 -0.2794)
			(end -0.12065 -0.3048)
			(stroke
				(width 0.1)
				(type default)
			)
			(layer "B.Fab")
		)
		(fp_line
			(start -0.12065 -0.3048)
			(end -0.67945 -0.3048)
			(stroke
				(width 0.1)
				(type default)
			)
			(layer "B.Fab")
		)
		(fp_line
			(start -0.67945 0.3048)
			(end -0.120396 0.3048)
			(stroke
				(width 0.1)
				(type default)
			)
			(layer "B.Fab")
		)
		(fp_line
			(start -0.67945 -0.3048)
			(end -0.67945 0.3048)
			(stroke
				(width 0.1)
				(type default)
			)
			(layer "B.Fab")
		)
		(pad "1" smd circle
			(at 0.40005 0)
			(size 0 0)
			(layers "B.Cu" "B.Mask" "B.Paste")
			(net "P3V3_AUX")
		)
		(pad "2" smd circle
			(at -0.40005 0)
			(size 0 0)
			(layers "B.Cu" "B.Mask" "B.Paste")
			(net "FM_UART_SWITCH_N")
		)
	)
)
